(kicad_pcb
	(version 20260206)
	(generator "pcbnew")
	(generator_version "10.0")
	(general
		(thickness 1.6)
		(legacy_teardrops no)
	)
	(paper "A4")
	(title_block
		(title "Bryce Canyon_F.DPB_16315-1-OCP.brd")
		(comment 1 "Bryce Canyon / footprints 430-436 of 2223")
	)
	(layers
		(0 "F.Cu" signal "TOP")
		(4 "In1.Cu" signal "L2GND")
		(6 "In2.Cu" signal "L3")
		(8 "In3.Cu" signal "L4GND")
		(10 "In4.Cu" signal "L5")
		(12 "In5.Cu" signal "L6VCC")
		(14 "In6.Cu" signal "L7VCC")
		(16 "In7.Cu" signal "L8")
		(18 "In8.Cu" signal "L9GND")
		(20 "In9.Cu" signal "L10")
		(22 "In10.Cu" signal "L11GND")
		(2 "B.Cu" signal "BOTTOM")
		(9 "F.Adhes" user "F.Adhesive")
		(11 "B.Adhes" user "B.Adhesive")
		(13 "F.Paste" user "Package Geometry/Pastemask Top")
		(15 "B.Paste" user "Package Geometry/Pastemask Bottom")
		(5 "F.SilkS" user "Ref Des/Silkscreen Top")
		(7 "B.SilkS" user "Ref Des/Silkscreen Bottom")
		(1 "F.Mask" user "Board Geometry/Soldermask Top")
		(3 "B.Mask" user "Board Geometry/Soldermask Bottom")
		(17 "Dwgs.User" user "User.Drawings")
		(19 "Cmts.User" user "User.Comments")
		(21 "Eco1.User" user "User.Eco1")
		(23 "Eco2.User" user "User.Eco2")
		(25 "Edge.Cuts" user "Board Geometry/Outline")
		(27 "Margin" user)
		(31 "F.CrtYd" user "Package Geometry/Place Bound Top")
		(29 "B.CrtYd" user "Package Geometry/Place Bound Bottom")
		(35 "F.Fab" user "Ref Des/Assembly Top")
		(33 "B.Fab" user "Ref Des/Assembly Bottom")
	)
	(footprint ""
		(layer "F.Cu")
		(at 79.84998 -31.404814 180)
		(property "Reference" "R1297"
			(at 0 0 180)
			(layer "F.SilkS")
			(hide yes)
			(effects
				(font
					(size 1.27 1.27)
				)
			)
		)
		(property "Value" "2K2R2F-GP"
			(at 0.064008 -3.993896 180)
			(unlocked yes)
			(layer "F.Fab")
			(hide yes)
			(effects
				(font
					(size 1.016 1.016)
					(thickness 0.1524)
				)
			)
		)
		(property "Device Type" "R402H16"
			(at 0.064008 -5.517896 180)
			(unlocked yes)
			(layer "F.Fab")
			(hide yes)
			(effects
				(font
					(size 1.016 1.016)
					(thickness 0.1524)
				)
			)
		)
		(duplicate_pad_numbers_are_jumpers no)
		(fp_line
			(start 0.508 -0.9398)
			(end -0.508 -0.9398)
			(stroke
				(width 0.1524)
				(type default)
			)
			(layer "F.SilkS")
		)
		(fp_line
			(start -0.508 -0.9398)
			(end -0.508 0.9398)
			(stroke
				(width 0.1524)
				(type default)
			)
			(layer "F.SilkS")
		)
		(fp_rect
			(start -0.508 0.9398)
			(end 0.508 -0.9398)
			(stroke
				(width 0)
				(type default)
			)
			(fill no)
			(layer "F.CrtYd")
		)
		(fp_rect
			(start -0.508 0.9398)
			(end 0.508 -0.9398)
			(stroke
				(width 0)
				(type default)
			)
			(fill no)
			(layer "F.Fab")
		)
		(pad "1" smd custom
			(at 0 -0.4445 180)
			(size 0.1397 0.1397)
			(layers "F.Cu" "F.Mask" "F.Paste")
			(net "P3V3_STBY_A")
			(options
				(clearance outline)
				(anchor circle)
			)
			(primitives
				(gr_poly
					(pts
						(arc
							(start -0.1778 -0.2794)
							(mid -0.249642 -0.249642)
							(end -0.2794 -0.1778)
						)
						(arc
							(start -0.2794 0.1778)
							(mid -0.249642 0.249642)
							(end -0.1778 0.2794)
						)
						(arc
							(start 0.1778 0.2794)
							(mid 0.249642 0.249642)
							(end 0.2794 0.1778)
						)
						(arc
							(start 0.2794 -0.1778)
							(mid 0.249642 -0.249642)
							(end 0.1778 -0.2794)
						)
					)
					(width 0)
					(fill yes)
				)
			)
		)
		(pad "2" smd custom
			(at 0 0.4445 180)
			(size 0.1397 0.1397)
			(layers "F.Cu" "F.Mask" "F.Paste")
			(net "I2C_BMC_A_MISC_SDA")
			(options
				(clearance outline)
				(anchor circle)
			)
			(primitives
				(gr_poly
					(pts
						(arc
							(start -0.1778 -0.2794)
							(mid -0.249642 -0.249642)
							(end -0.2794 -0.1778)
						)
						(arc
							(start -0.2794 0.1778)
							(mid -0.249642 0.249642)
							(end -0.1778 0.2794)
						)
						(arc
							(start 0.1778 0.2794)
							(mid 0.249642 0.249642)
							(end 0.2794 0.1778)
						)
						(arc
							(start 0.2794 -0.1778)
							(mid 0.249642 -0.249642)
							(end 0.1778 -0.2794)
						)
					)
					(width 0)
					(fill yes)
				)
			)
		)
	)
	(footprint ""
		(layer "F.Cu")
		(at 98.897948 -292.169342 -90)
		(property "Reference" "R177"
			(at 0 0 270)
			(layer "F.SilkS")
			(hide yes)
			(effects
				(font
					(size 1.27 1.27)
				)
			)
		)
		(property "Value" "10KR2F-2-GP"
			(at 0.064008 -3.993896 270)
			(unlocked yes)
			(layer "F.Fab")
			(hide yes)
			(effects
				(font
					(size 1.016 1.016)
					(thickness 0.1524)
				)
			)
		)
		(property "Device Type" "R402H16"
			(at 0.064008 -5.517896 270)
			(unlocked yes)
			(layer "F.Fab")
			(hide yes)
			(effects
				(font
					(size 1.016 1.016)
					(thickness 0.1524)
				)
			)
		)
		(duplicate_pad_numbers_are_jumpers no)
		(fp_line
			(start -0.508 -0.9398)
			(end -0.508 0.9398)
			(stroke
				(width 0.1524)
				(type default)
			)
			(layer "F.SilkS")
		)
		(fp_line
			(start 0.508 -0.9398)
			(end -0.508 -0.9398)
			(stroke
				(width 0.1524)
				(type default)
			)
			(layer "F.SilkS")
		)
		(fp_rect
			(start -0.508 0.9398)
			(end 0.508 -0.9398)
			(stroke
				(width 0)
				(type default)
			)
			(fill no)
			(layer "F.CrtYd")
		)
		(fp_rect
			(start -0.508 0.9398)
			(end 0.508 -0.9398)
			(stroke
				(width 0)
				(type default)
			)
			(fill no)
			(layer "F.Fab")
		)
		(pad "1" smd custom
			(at 0 -0.4445 270)
			(size 0.1397 0.1397)
			(layers "F.Cu" "F.Mask" "F.Paste")
			(net "P3V3_STBY_A")
			(options
				(clearance outline)
				(anchor circle)
			)
			(primitives
				(gr_poly
					(pts
						(arc
							(start -0.1778 -0.2794)
							(mid -0.249642 -0.249642)
							(end -0.2794 -0.1778)
						)
						(arc
							(start -0.2794 0.1778)
							(mid -0.249642 0.249642)
							(end -0.1778 0.2794)
						)
						(arc
							(start 0.1778 0.2794)
							(mid 0.249642 0.249642)
							(end 0.2794 0.1778)
						)
						(arc
							(start 0.2794 -0.1778)
							(mid 0.249642 -0.249642)
							(end 0.1778 -0.2794)
						)
					)
					(width 0)
					(fill yes)
				)
			)
		)
		(pad "2" smd custom
			(at 0 0.4445 270)
			(size 0.1397 0.1397)
			(layers "F.Cu" "F.Mask" "F.Paste")
			(net "HDD_PRSNT_2")
			(options
				(clearance outline)
				(anchor circle)
			)
			(primitives
				(gr_poly
					(pts
						(arc
							(start -0.1778 -0.2794)
							(mid -0.249642 -0.249642)
							(end -0.2794 -0.1778)
						)
						(arc
							(start -0.2794 0.1778)
							(mid -0.249642 0.249642)
							(end -0.1778 0.2794)
						)
						(arc
							(start 0.1778 0.2794)
							(mid 0.249642 0.249642)
							(end 0.2794 0.1778)
						)
						(arc
							(start 0.2794 -0.1778)
							(mid 0.249642 -0.249642)
							(end 0.1778 -0.2794)
						)
					)
					(width 0)
					(fill yes)
				)
			)
		)
	)
	(footprint ""
		(layer "F.Cu")
		(at 149.196298 -159.871918 -90)
		(property "Reference" "R509"
			(at 0 0 270)
			(layer "F.SilkS")
			(hide yes)
			(effects
				(font
					(size 1.27 1.27)
				)
			)
		)
		(property "Value" "0R2J-2-GP"
			(at 0.064008 -3.993896 270)
			(unlocked yes)
			(layer "F.Fab")
			(hide yes)
			(effects
				(font
					(size 1.016 1.016)
					(thickness 0.1524)
				)
			)
		)
		(property "Device Type" "R402H16"
			(at 0.064008 -5.517896 270)
			(unlocked yes)
			(layer "F.Fab")
			(hide yes)
			(effects
				(font
					(size 1.016 1.016)
					(thickness 0.1524)
				)
			)
		)
		(duplicate_pad_numbers_are_jumpers no)
		(fp_line
			(start -0.508 -0.9398)
			(end -0.508 0.9398)
			(stroke
				(width 0.1524)
				(type default)
			)
			(layer "F.SilkS")
		)
		(fp_line
			(start 0.508 -0.9398)
			(end -0.508 -0.9398)
			(stroke
				(width 0.1524)
				(type default)
			)
			(layer "F.SilkS")
		)
		(fp_rect
			(start -0.508 0.9398)
			(end 0.508 -0.9398)
			(stroke
				(width 0)
				(type default)
			)
			(fill no)
			(layer "F.CrtYd")
		)
		(fp_rect
			(start -0.508 0.9398)
			(end 0.508 -0.9398)
			(stroke
				(width 0)
				(type default)
			)
			(fill no)
			(layer "F.Fab")
		)
		(pad "1" smd custom
			(at 0 -0.4445 270)
			(size 0.1397 0.1397)
			(layers "F.Cu" "F.Mask" "F.Paste")
			(net "DRIVE_A_16_PWR")
			(options
				(clearance outline)
				(anchor circle)
			)
			(primitives
				(gr_poly
					(pts
						(arc
							(start -0.1778 -0.2794)
							(mid -0.249642 -0.249642)
							(end -0.2794 -0.1778)
						)
						(arc
							(start -0.2794 0.1778)
							(mid -0.249642 0.249642)
							(end -0.1778 0.2794)
						)
						(arc
							(start 0.1778 0.2794)
							(mid 0.249642 0.249642)
							(end 0.2794 0.1778)
						)
						(arc
							(start 0.2794 -0.1778)
							(mid 0.249642 -0.249642)
							(end 0.1778 -0.2794)
						)
					)
					(width 0)
					(fill yes)
				)
			)
		)
		(pad "2" smd custom
			(at 0 0.4445 270)
			(size 0.1397 0.1397)
			(layers "F.Cu" "F.Mask" "F.Paste")
			(net "SW_PWR_R_HDD16")
			(options
				(clearance outline)
				(anchor circle)
			)
			(primitives
				(gr_poly
					(pts
						(arc
							(start -0.1778 -0.2794)
							(mid -0.249642 -0.249642)
							(end -0.2794 -0.1778)
						)
						(arc
							(start -0.2794 0.1778)
							(mid -0.249642 0.249642)
							(end -0.1778 0.2794)
						)
						(arc
							(start 0.1778 0.2794)
							(mid 0.249642 0.249642)
							(end 0.2794 0.1778)
						)
						(arc
							(start 0.2794 -0.1778)
							(mid 0.249642 -0.249642)
							(end 0.1778 -0.2794)
						)
					)
					(width 0)
					(fill yes)
				)
			)
		)
	)
	(footprint ""
		(layer "F.Cu")
		(at 338.709 -56.809894 -90)
		(property "Reference" "R835"
			(at 0 0 270)
			(layer "F.SilkS")
			(hide yes)
			(effects
				(font
					(size 1.27 1.27)
				)
			)
		)
		(property "Value" "300KR2F-GP"
			(at 0.064008 -3.993896 270)
			(unlocked yes)
			(layer "F.Fab")
			(hide yes)
			(effects
				(font
					(size 1.016 1.016)
					(thickness 0.1524)
				)
			)
		)
		(property "Device Type" "R402H16"
			(at 0.064008 -5.517896 270)
			(unlocked yes)
			(layer "F.Fab")
			(hide yes)
			(effects
				(font
					(size 1.016 1.016)
					(thickness 0.1524)
				)
			)
		)
		(duplicate_pad_numbers_are_jumpers no)
		(fp_line
			(start -0.508 -0.9398)
			(end -0.508 0.9398)
			(stroke
				(width 0.1524)
				(type default)
			)
			(layer "F.SilkS")
		)
		(fp_line
			(start 0.508 -0.9398)
			(end -0.508 -0.9398)
			(stroke
				(width 0.1524)
				(type default)
			)
			(layer "F.SilkS")
		)
		(fp_rect
			(start -0.508 0.9398)
			(end 0.508 -0.9398)
			(stroke
				(width 0)
				(type default)
			)
			(fill no)
			(layer "F.CrtYd")
		)
		(fp_rect
			(start -0.508 0.9398)
			(end 0.508 -0.9398)
			(stroke
				(width 0)
				(type default)
			)
			(fill no)
			(layer "F.Fab")
		)
		(pad "1" smd custom
			(at 0 -0.4445 270)
			(size 0.1397 0.1397)
			(layers "F.Cu" "F.Mask" "F.Paste")
			(net "SW_HDD_N30")
			(options
				(clearance outline)
				(anchor circle)
			)
			(primitives
				(gr_poly
					(pts
						(arc
							(start -0.1778 -0.2794)
							(mid -0.249642 -0.249642)
							(end -0.2794 -0.1778)
						)
						(arc
							(start -0.2794 0.1778)
							(mid -0.249642 0.249642)
							(end -0.1778 0.2794)
						)
						(arc
							(start 0.1778 0.2794)
							(mid 0.249642 0.249642)
							(end 0.2794 0.1778)
						)
						(arc
							(start 0.2794 -0.1778)
							(mid 0.249642 -0.249642)
							(end 0.1778 -0.2794)
						)
					)
					(width 0)
					(fill yes)
				)
			)
		)
		(pad "2" smd custom
			(at 0 0.4445 270)
			(size 0.1397 0.1397)
			(layers "F.Cu" "F.Mask" "F.Paste")
			(net "P12V_A")
			(options
				(clearance outline)
				(anchor circle)
			)
			(primitives
				(gr_poly
					(pts
						(arc
							(start -0.1778 -0.2794)
							(mid -0.249642 -0.249642)
							(end -0.2794 -0.1778)
						)
						(arc
							(start -0.2794 0.1778)
							(mid -0.249642 0.249642)
							(end -0.1778 0.2794)
						)
						(arc
							(start 0.1778 0.2794)
							(mid 0.249642 0.249642)
							(end 0.2794 0.1778)
						)
						(arc
							(start 0.2794 -0.1778)
							(mid 0.249642 -0.249642)
							(end 0.1778 -0.2794)
						)
					)
					(width 0)
					(fill yes)
				)
			)
		)
	)
	(footprint ""
		(layer "F.Cu")
		(at 392.91895 -296.842942 180)
		(property "Reference" "C144"
			(at 0 0 180)
			(layer "F.SilkS")
			(hide yes)
			(effects
				(font
					(size 1.27 1.27)
				)
			)
		)
		(property "Value" "SC1U16V3KX-5GP"
			(at 0 -2.8194 180)
			(unlocked yes)
			(layer "F.Fab")
			(hide yes)
			(effects
				(font
					(size 1.016 1.016)
					(thickness 0.1524)
				)
			)
		)
		(property "Device Type" "C603H36"
			(at 0 -4.3434 180)
			(unlocked yes)
			(layer "F.Fab")
			(hide yes)
			(effects
				(font
					(size 1.016 1.016)
					(thickness 0.1524)
				)
			)
		)
		(duplicate_pad_numbers_are_jumpers no)
		(fp_line
			(start 0.508 0)
			(end -0.508 0)
			(stroke
				(width 0.2032)
				(type default)
			)
			(layer "F.SilkS")
		)
		(fp_rect
			(start -0.5842 1.3335)
			(end 0.5842 -1.3335)
			(stroke
				(width 0)
				(type default)
			)
			(fill no)
			(layer "F.CrtYd")
		)
		(fp_rect
			(start -0.5842 1.3335)
			(end 0.5842 -1.3335)
			(stroke
				(width 0)
				(type default)
			)
			(fill no)
			(layer "F.Fab")
		)
		(pad "1" smd custom
			(at 0 -0.762 180)
			(size 0.2159 0.2159)
			(layers "F.Cu" "F.Mask" "F.Paste")
			(net "P5V_HDD8")
			(options
				(clearance outline)
				(anchor circle)
			)
			(primitives
				(gr_poly
					(pts
						(arc
							(start -0.3302 -0.4318)
							(mid -0.402042 -0.402042)
							(end -0.4318 -0.3302)
						)
						(arc
							(start -0.4318 0.3302)
							(mid -0.402042 0.402042)
							(end -0.3302 0.4318)
						)
						(arc
							(start 0.3302 0.4318)
							(mid 0.402042 0.402042)
							(end 0.4318 0.3302)
						)
						(arc
							(start 0.4318 -0.3302)
							(mid 0.402042 -0.402042)
							(end 0.3302 -0.4318)
						)
					)
					(width 0)
					(fill yes)
				)
			)
		)
		(pad "2" smd custom
			(at 0 0.762 180)
			(size 0.2159 0.2159)
			(layers "F.Cu" "F.Mask" "F.Paste")
			(net "GND")
			(options
				(clearance outline)
				(anchor circle)
			)
			(primitives
				(gr_poly
					(pts
						(arc
							(start -0.3302 -0.4318)
							(mid -0.402042 -0.402042)
							(end -0.4318 -0.3302)
						)
						(arc
							(start -0.4318 0.3302)
							(mid -0.402042 0.402042)
							(end -0.3302 0.4318)
						)
						(arc
							(start 0.3302 0.4318)
							(mid 0.402042 0.402042)
							(end 0.4318 0.3302)
						)
						(arc
							(start 0.4318 -0.3302)
							(mid 0.402042 -0.402042)
							(end 0.3302 -0.4318)
						)
					)
					(width 0)
					(fill yes)
				)
			)
		)
	)
	(footprint ""
		(layer "F.Cu")
		(at 333.329534 -23.07717 90)
		(property "Reference" "R75"
			(at 0 0 90)
			(layer "F.SilkS")
			(hide yes)
			(effects
				(font
					(size 1.27 1.27)
				)
			)
		)
		(property "Value" "100KR2F-L1-GP"
			(at 0.064008 -3.993896 90)
			(unlocked yes)
			(layer "F.Fab")
			(hide yes)
			(effects
				(font
					(size 1.016 1.016)
					(thickness 0.1524)
				)
			)
		)
		(property "Device Type" "R402H16"
			(at 0.064008 -5.517896 90)
			(unlocked yes)
			(layer "F.Fab")
			(hide yes)
			(effects
				(font
					(size 1.016 1.016)
					(thickness 0.1524)
				)
			)
		)
		(duplicate_pad_numbers_are_jumpers no)
		(fp_line
			(start 0.508 -0.9398)
			(end -0.508 -0.9398)
			(stroke
				(width 0.1524)
				(type default)
			)
			(layer "F.SilkS")
		)
		(fp_line
			(start -0.508 -0.9398)
			(end -0.508 0.9398)
			(stroke
				(width 0.1524)
				(type default)
			)
			(layer "F.SilkS")
		)
		(fp_rect
			(start -0.508 0.9398)
			(end 0.508 -0.9398)
			(stroke
				(width 0)
				(type default)
			)
			(fill no)
			(layer "F.CrtYd")
		)
		(fp_rect
			(start -0.508 0.9398)
			(end 0.508 -0.9398)
			(stroke
				(width 0)
				(type default)
			)
			(fill no)
			(layer "F.Fab")
		)
		(pad "1" smd custom
			(at 0 -0.4445 90)
			(size 0.1397 0.1397)
			(layers "F.Cu" "F.Mask" "F.Paste")
			(net "P3V3_STBY_B")
			(options
				(clearance outline)
				(anchor circle)
			)
			(primitives
				(gr_poly
					(pts
						(arc
							(start -0.1778 -0.2794)
							(mid -0.249642 -0.249642)
							(end -0.2794 -0.1778)
						)
						(arc
							(start -0.2794 0.1778)
							(mid -0.249642 0.249642)
							(end -0.1778 0.2794)
						)
						(arc
							(start 0.1778 0.2794)
							(mid 0.249642 0.249642)
							(end 0.2794 0.1778)
						)
						(arc
							(start 0.2794 -0.1778)
							(mid 0.249642 -0.249642)
							(end 0.1778 -0.2794)
						)
					)
					(width 0)
					(fill yes)
				)
			)
		)
		(pad "2" smd custom
			(at 0 0.4445 90)
			(size 0.1397 0.1397)
			(layers "F.Cu" "F.Mask" "F.Paste")
			(net "BMC_B_MISC_ALERT_N")
			(options
				(clearance outline)
				(anchor circle)
			)
			(primitives
				(gr_poly
					(pts
						(arc
							(start -0.1778 -0.2794)
							(mid -0.249642 -0.249642)
							(end -0.2794 -0.1778)
						)
						(arc
							(start -0.2794 0.1778)
							(mid -0.249642 0.249642)
							(end -0.1778 0.2794)
						)
						(arc
							(start 0.1778 0.2794)
							(mid 0.249642 0.249642)
							(end 0.2794 0.1778)
						)
						(arc
							(start 0.2794 -0.1778)
							(mid 0.249642 -0.249642)
							(end 0.1778 -0.2794)
						)
					)
					(width 0)
					(fill yes)
				)
			)
		)
	)
	(footprint ""
		(layer "F.Cu")
		(at 393.90955 -287.597342 -90)
		(property "Reference" "R321"
			(at 0 0 270)
			(layer "F.SilkS")
			(hide yes)
			(effects
				(font
					(size 1.27 1.27)
				)
			)
		)
		(property "Value" "4K7R2J-2-GP"
			(at 0.064008 -3.993896 270)
			(unlocked yes)
			(layer "F.Fab")
			(hide yes)
			(effects
				(font
					(size 1.016 1.016)
					(thickness 0.1524)
				)
			)
		)
		(property "Device Type" "R402H16"
			(at 0.064008 -5.517896 270)
			(unlocked yes)
			(layer "F.Fab")
			(hide yes)
			(effects
				(font
					(size 1.016 1.016)
					(thickness 0.1524)
				)
			)
		)
		(duplicate_pad_numbers_are_jumpers no)
		(fp_line
			(start -0.508 -0.9398)
			(end -0.508 0.9398)
			(stroke
				(width 0.1524)
				(type default)
			)
			(layer "F.SilkS")
		)
		(fp_line
			(start 0.508 -0.9398)
			(end -0.508 -0.9398)
			(stroke
				(width 0.1524)
				(type default)
			)
			(layer "F.SilkS")
		)
		(fp_rect
			(start -0.508 0.9398)
			(end 0.508 -0.9398)
			(stroke
				(width 0)
				(type default)
			)
			(fill no)
			(layer "F.CrtYd")
		)
		(fp_rect
			(start -0.508 0.9398)
			(end 0.508 -0.9398)
			(stroke
				(width 0)
				(type default)
			)
			(fill no)
			(layer "F.Fab")
		)
		(pad "1" smd custom
			(at 0 -0.4445 270)
			(size 0.1397 0.1397)
			(layers "F.Cu" "F.Mask" "F.Paste")
			(net "P12V_A")
			(options
				(clearance outline)
				(anchor circle)
			)
			(primitives
				(gr_poly
					(pts
						(arc
							(start -0.1778 -0.2794)
							(mid -0.249642 -0.249642)
							(end -0.2794 -0.1778)
						)
						(arc
							(start -0.2794 0.1778)
							(mid -0.249642 0.249642)
							(end -0.1778 0.2794)
						)
						(arc
							(start 0.1778 0.2794)
							(mid 0.249642 0.249642)
							(end 0.2794 0.1778)
						)
						(arc
							(start 0.2794 -0.1778)
							(mid 0.249642 -0.249642)
							(end 0.1778 -0.2794)
						)
					)
					(width 0)
					(fill yes)
				)
			)
		)
		(pad "2" smd custom
			(at 0 0.4445 270)
			(size 0.1397 0.1397)
			(layers "F.Cu" "F.Mask" "F.Paste")
			(net "SW_HDD_P8")
			(options
				(clearance outline)
				(anchor circle)
			)
			(primitives
				(gr_poly
					(pts
						(arc
							(start -0.1778 -0.2794)
							(mid -0.249642 -0.249642)
							(end -0.2794 -0.1778)
						)
						(arc
							(start -0.2794 0.1778)
							(mid -0.249642 0.249642)
							(end -0.1778 0.2794)
						)
						(arc
							(start 0.1778 0.2794)
							(mid 0.249642 0.249642)
							(end 0.2794 0.1778)
						)
						(arc
							(start 0.2794 -0.1778)
							(mid 0.249642 -0.249642)
							(end 0.1778 -0.2794)
						)
					)
					(width 0)
					(fill yes)
				)
			)
		)
	)
)
